# T6G (Grand Teton) — schematic netlist excerpt (pin names and nets, part order shuffled) for the footprints in the layout excerpt that follows; sources: Cadence DE-HDL packaged netlist, KiCad conversion of 04192023_DAF0TMB3IC0_F0TG_MB_C_brd_V02_OCP.brd

PR446  Q_RES  0 5% EMPTY  pkg 0402LF  page 194 : A = PVDDCR_CPU0_P0_PVCC ; B = P3V3_AUX
R3666  Q_RES  0 5% CHIP  pkg 0402LF  page 234 : A = USB_HUB_TEST ; B = GND

(kicad_pcb
	(version 20260206)
	(generator "pcbnew")
	(generator_version "10.0")
	(general
		(thickness 1.6)
		(legacy_teardrops no)
	)
	(paper "A4")
	(title_block
		(title "04192023_DAF0TMB3IC0_F0TG_MB_C_brd_V02_OCP.brd")
		(comment 1 "Grand Teton / footprints 4260-4261 of 8354")
	)
	(layers
		(0 "F.Cu" signal "TOP")
		(4 "In1.Cu" signal "GND")
		(6 "In2.Cu" signal "IN1")
		(8 "In3.Cu" signal "GND1")
		(10 "In4.Cu" signal "IN2")
		(12 "In5.Cu" signal "GND2")
		(14 "In6.Cu" signal "IN3")
		(16 "In7.Cu" signal "GND3")
		(18 "In8.Cu" signal "VCC")
		(20 "In9.Cu" signal "VCC1")
		(22 "In10.Cu" signal "GND4")
		(24 "In11.Cu" signal "IN4")
		(26 "In12.Cu" signal "GND5")
		(28 "In13.Cu" signal "IN5")
		(30 "In14.Cu" signal "GND6")
		(32 "In15.Cu" signal "IN6")
		(34 "In16.Cu" signal "GND7")
		(2 "B.Cu" signal "BOTTOM")
		(9 "F.Adhes" user "F.Adhesive")
		(11 "B.Adhes" user "B.Adhesive")
		(13 "F.Paste" user "Package Geometry/Pastemask Top")
		(15 "B.Paste" user "Package Geometry/Pastemask Bottom")
		(5 "F.SilkS" user "Ref Des/Silkscreen Top")
		(7 "B.SilkS" user "Ref Des/Silkscreen Bottom")
		(1 "F.Mask" user "Board Geometry/Soldermask Top")
		(3 "B.Mask" user "Board Geometry/Soldermask Bottom")
		(17 "Dwgs.User" user "User.Drawings")
		(19 "Cmts.User" user "User.Comments")
		(21 "Eco1.User" user "User.Eco1")
		(23 "Eco2.User" user "User.Eco2")
		(25 "Edge.Cuts" user "Board Geometry/Outline")
		(27 "Margin" user)
		(31 "F.CrtYd" user "Package Geometry/Place Bound Top")
		(29 "B.CrtYd" user "Package Geometry/Place Bound Bottom")
		(35 "F.Fab" user "Ref Des/Assembly Top")
		(33 "B.Fab" user "Ref Des/Assembly Bottom")
	)
	(footprint ""
		(layer "F.Cu")
		(at 14.01826 -92.687648 -90)
		(property "Reference" "R3666"
			(at 0 0 270)
			(layer "F.SilkS")
			(hide yes)
			(effects
				(font
					(size 1.27 1.27)
				)
			)
		)
		(property "Value" ""
			(at 0 0 270)
			(layer "F.Fab")
			(effects
				(font
					(size 1.27 1.27)
				)
			)
		)
		(duplicate_pad_numbers_are_jumpers no)
		(fp_line
			(start -0.7874 0.4064)
			(end -0.7874 -0.4064)
			(stroke
				(width 0.1524)
				(type default)
			)
			(layer "F.SilkS")
		)
		(fp_line
			(start 0.7874 0.4064)
			(end -0.7874 0.4064)
			(stroke
				(width 0.1524)
				(type default)
			)
			(layer "F.SilkS")
		)
		(fp_line
			(start -0.7874 -0.4064)
			(end 0.7874 -0.4064)
			(stroke
				(width 0.1524)
				(type default)
			)
			(layer "F.SilkS")
		)
		(fp_line
			(start 0.7874 -0.4064)
			(end 0.7874 0.4064)
			(stroke
				(width 0.1524)
				(type default)
			)
			(layer "F.SilkS")
		)
		(fp_line
			(start -0.67945 0.3048)
			(end -0.67945 -0.305054)
			(stroke
				(width 0.1)
				(type default)
			)
			(layer "F.Fab")
		)
		(fp_line
			(start -0.12065 0.3048)
			(end -0.67945 0.3048)
			(stroke
				(width 0.1)
				(type default)
			)
			(layer "F.Fab")
		)
		(fp_line
			(start 0.120396 0.3048)
			(end 0.120396 0.2794)
			(stroke
				(width 0.1)
				(type default)
			)
			(layer "F.Fab")
		)
		(fp_line
			(start 0.67945 0.3048)
			(end 0.120396 0.3048)
			(stroke
				(width 0.1)
				(type default)
			)
			(layer "F.Fab")
		)
		(fp_line
			(start -0.12065 0.2794)
			(end -0.12065 0.3048)
			(stroke
				(width 0.1)
				(type default)
			)
			(layer "F.Fab")
		)
		(fp_line
			(start 0.120396 0.2794)
			(end -0.12065 0.2794)
			(stroke
				(width 0.1)
				(type default)
			)
			(layer "F.Fab")
		)
		(fp_line
			(start -0.12065 -0.2794)
			(end 0.12065 -0.2794)
			(stroke
				(width 0.1)
				(type default)
			)
			(layer "F.Fab")
		)
		(fp_line
			(start 0.12065 -0.2794)
			(end 0.12065 -0.3048)
			(stroke
				(width 0.1)
				(type default)
			)
			(layer "F.Fab")
		)
		(fp_line
			(start 0.12065 -0.3048)
			(end 0.67945 -0.3048)
			(stroke
				(width 0.1)
				(type default)
			)
			(layer "F.Fab")
		)
		(fp_line
			(start 0.67945 -0.3048)
			(end 0.67945 0.3048)
			(stroke
				(width 0.1)
				(type default)
			)
			(layer "F.Fab")
		)
		(fp_line
			(start -0.67945 -0.305054)
			(end -0.12065 -0.305054)
			(stroke
				(width 0.1)
				(type default)
			)
			(layer "F.Fab")
		)
		(fp_line
			(start -0.12065 -0.305054)
			(end -0.12065 -0.2794)
			(stroke
				(width 0.1)
				(type default)
			)
			(layer "F.Fab")
		)
		(pad "1" smd circle
			(at -0.40005 0 270)
			(size 0 0)
			(layers "F.Cu" "F.Mask" "F.Paste")
			(net "USB_HUB_TEST")
		)
		(pad "2" smd circle
			(at 0.40005 0 270)
			(size 0 0)
			(layers "F.Cu" "F.Mask" "F.Paste")
			(net "GND")
		)
	)
	(footprint ""
		(layer "F.Cu")
		(at 419.094666 -157.618684 -90)
		(property "Reference" "PR446"
			(at 0 0 270)
			(layer "F.SilkS")
			(hide yes)
			(effects
				(font
					(size 1.27 1.27)
				)
			)
		)
		(property "Value" ""
			(at 0 0 270)
			(layer "F.Fab")
			(effects
				(font
					(size 1.27 1.27)
				)
			)
		)
		(duplicate_pad_numbers_are_jumpers no)
		(fp_line
			(start -0.7874 0.4064)
			(end -0.7874 -0.4064)
			(stroke
				(width 0.1524)
				(type default)
			)
			(layer "F.SilkS")
		)
		(fp_line
			(start 0.7874 0.4064)
			(end -0.7874 0.4064)
			(stroke
				(width 0.1524)
				(type default)
			)
			(layer "F.SilkS")
		)
		(fp_line
			(start -0.7874 -0.4064)
			(end 0.7874 -0.4064)
			(stroke
				(width 0.1524)
				(type default)
			)
			(layer "F.SilkS")
		)
		(fp_line
			(start 0.7874 -0.4064)
			(end 0.7874 0.4064)
			(stroke
				(width 0.1524)
				(type default)
			)
			(layer "F.SilkS")
		)
		(fp_line
			(start -0.67945 0.3048)
			(end -0.67945 -0.305054)
			(stroke
				(width 0.1)
				(type default)
			)
			(layer "F.Fab")
		)
		(fp_line
			(start -0.12065 0.3048)
			(end -0.67945 0.3048)
			(stroke
				(width 0.1)
				(type default)
			)
			(layer "F.Fab")
		)
		(fp_line
			(start 0.120396 0.3048)
			(end 0.120396 0.2794)
			(stroke
				(width 0.1)
				(type default)
			)
			(layer "F.Fab")
		)
		(fp_line
			(start 0.67945 0.3048)
			(end 0.120396 0.3048)
			(stroke
				(width 0.1)
				(type default)
			)
			(layer "F.Fab")
		)
		(fp_line
			(start -0.12065 0.2794)
			(end -0.12065 0.3048)
			(stroke
				(width 0.1)
				(type default)
			)
			(layer "F.Fab")
		)
		(fp_line
			(start 0.120396 0.2794)
			(end -0.12065 0.2794)
			(stroke
				(width 0.1)
				(type default)
			)
			(layer "F.Fab")
		)
		(fp_line
			(start -0.12065 -0.2794)
			(end 0.12065 -0.2794)
			(stroke
				(width 0.1)
				(type default)
			)
			(layer "F.Fab")
		)
		(fp_line
			(start 0.12065 -0.2794)
			(end 0.12065 -0.3048)
			(stroke
				(width 0.1)
				(type default)
			)
			(layer "F.Fab")
		)
		(fp_line
			(start 0.12065 -0.3048)
			(end 0.67945 -0.3048)
			(stroke
				(width 0.1)
				(type default)
			)
			(layer "F.Fab")
		)
		(fp_line
			(start 0.67945 -0.3048)
			(end 0.67945 0.3048)
			(stroke
				(width 0.1)
				(type default)
			)
			(layer "F.Fab")
		)
		(fp_line
			(start -0.67945 -0.305054)
			(end -0.12065 -0.305054)
			(stroke
				(width 0.1)
				(type default)
			)
			(layer "F.Fab")
		)
		(fp_line
			(start -0.12065 -0.305054)
			(end -0.12065 -0.2794)
			(stroke
				(width 0.1)
				(type default)
			)
			(layer "F.Fab")
		)
		(pad "1" smd circle
			(at -0.40005 0 270)
			(size 0 0)
			(layers "F.Cu" "F.Mask" "F.Paste")
			(net "PVDDCR_CPU0_P0_PVCC")
		)
		(pad "2" smd circle
			(at 0.40005 0 270)
			(size 0 0)
			(layers "F.Cu" "F.Mask" "F.Paste")
			(net "P3V3_AUX")
		)
	)
)
